# T6G (Grand Teton) — schematic netlist excerpt (pin names and nets, part order shuffled) for the footprints in the layout excerpt that follows; sources: Cadence DE-HDL packaged netlist, KiCad conversion of 04192023_DAF0TMB3IC0_F0TG_MB_C_brd_V02_OCP.brd

C1713  Q_CAP  0.1UF 25V 10% X7R  pkg 0402  page 245 : A = P3V3_AUX ; B = GND
C3895  Q_CAP  22UF 4V 20% X6S  pkg C0402  page 68 : A = PVDDCR_SOC_P0 ; B = GND

(kicad_pcb
	(version 20260206)
	(generator "pcbnew")
	(generator_version "10.0")
	(general
		(thickness 1.6)
		(legacy_teardrops no)
	)
	(paper "A4")
	(title_block
		(title "04192023_DAF0TMB3IC0_F0TG_MB_C_brd_V02_OCP.brd")
		(comment 1 "Grand Teton / footprints 666-667 of 8354")
	)
	(layers
		(0 "F.Cu" signal "TOP")
		(4 "In1.Cu" signal "GND")
		(6 "In2.Cu" signal "IN1")
		(8 "In3.Cu" signal "GND1")
		(10 "In4.Cu" signal "IN2")
		(12 "In5.Cu" signal "GND2")
		(14 "In6.Cu" signal "IN3")
		(16 "In7.Cu" signal "GND3")
		(18 "In8.Cu" signal "VCC")
		(20 "In9.Cu" signal "VCC1")
		(22 "In10.Cu" signal "GND4")
		(24 "In11.Cu" signal "IN4")
		(26 "In12.Cu" signal "GND5")
		(28 "In13.Cu" signal "IN5")
		(30 "In14.Cu" signal "GND6")
		(32 "In15.Cu" signal "IN6")
		(34 "In16.Cu" signal "GND7")
		(2 "B.Cu" signal "BOTTOM")
		(9 "F.Adhes" user "F.Adhesive")
		(11 "B.Adhes" user "B.Adhesive")
		(13 "F.Paste" user "Package Geometry/Pastemask Top")
		(15 "B.Paste" user "Package Geometry/Pastemask Bottom")
		(5 "F.SilkS" user "Ref Des/Silkscreen Top")
		(7 "B.SilkS" user "Ref Des/Silkscreen Bottom")
		(1 "F.Mask" user "Board Geometry/Soldermask Top")
		(3 "B.Mask" user "Board Geometry/Soldermask Bottom")
		(17 "Dwgs.User" user "User.Drawings")
		(19 "Cmts.User" user "User.Comments")
		(21 "Eco1.User" user "User.Eco1")
		(23 "Eco2.User" user "User.Eco2")
		(25 "Edge.Cuts" user "Board Geometry/Outline")
		(27 "Margin" user)
		(31 "F.CrtYd" user "Package Geometry/Place Bound Top")
		(29 "B.CrtYd" user "Package Geometry/Place Bound Bottom")
		(35 "F.Fab" user "Ref Des/Assembly Top")
		(33 "B.Fab" user "Ref Des/Assembly Bottom")
	)
	(footprint ""
		(layer "F.Cu")
		(at 179.482242 -422.802304 -90)
		(property "Reference" "C1713"
			(at 0 0 270)
			(layer "F.SilkS")
			(hide yes)
			(effects
				(font
					(size 1.27 1.27)
				)
			)
		)
		(property "Value" ""
			(at 0 0 270)
			(layer "F.Fab")
			(effects
				(font
					(size 1.27 1.27)
				)
			)
		)
		(duplicate_pad_numbers_are_jumpers no)
		(fp_line
			(start -0.7874 0.4064)
			(end -0.7874 -0.4064)
			(stroke
				(width 0.1524)
				(type default)
			)
			(layer "F.SilkS")
		)
		(fp_line
			(start 0.7874 0.4064)
			(end -0.7874 0.4064)
			(stroke
				(width 0.1524)
				(type default)
			)
			(layer "F.SilkS")
		)
		(fp_line
			(start -0.7874 -0.4064)
			(end 0.7874 -0.4064)
			(stroke
				(width 0.1524)
				(type default)
			)
			(layer "F.SilkS")
		)
		(fp_line
			(start 0.7874 -0.4064)
			(end 0.7874 0.4064)
			(stroke
				(width 0.1524)
				(type default)
			)
			(layer "F.SilkS")
		)
		(fp_line
			(start -0.67945 0.3048)
			(end -0.67945 -0.305054)
			(stroke
				(width 0.1)
				(type default)
			)
			(layer "F.Fab")
		)
		(fp_line
			(start -0.12065 0.3048)
			(end -0.67945 0.3048)
			(stroke
				(width 0.1)
				(type default)
			)
			(layer "F.Fab")
		)
		(fp_line
			(start 0.120396 0.3048)
			(end 0.120396 0.2794)
			(stroke
				(width 0.1)
				(type default)
			)
			(layer "F.Fab")
		)
		(fp_line
			(start 0.67945 0.3048)
			(end 0.120396 0.3048)
			(stroke
				(width 0.1)
				(type default)
			)
			(layer "F.Fab")
		)
		(fp_line
			(start -0.12065 0.2794)
			(end -0.12065 0.3048)
			(stroke
				(width 0.1)
				(type default)
			)
			(layer "F.Fab")
		)
		(fp_line
			(start 0.120396 0.2794)
			(end -0.12065 0.2794)
			(stroke
				(width 0.1)
				(type default)
			)
			(layer "F.Fab")
		)
		(fp_line
			(start -0.12065 -0.2794)
			(end 0.12065 -0.2794)
			(stroke
				(width 0.1)
				(type default)
			)
			(layer "F.Fab")
		)
		(fp_line
			(start 0.12065 -0.2794)
			(end 0.12065 -0.3048)
			(stroke
				(width 0.1)
				(type default)
			)
			(layer "F.Fab")
		)
		(fp_line
			(start 0.12065 -0.3048)
			(end 0.67945 -0.3048)
			(stroke
				(width 0.1)
				(type default)
			)
			(layer "F.Fab")
		)
		(fp_line
			(start 0.67945 -0.3048)
			(end 0.67945 0.3048)
			(stroke
				(width 0.1)
				(type default)
			)
			(layer "F.Fab")
		)
		(fp_line
			(start -0.67945 -0.305054)
			(end -0.12065 -0.305054)
			(stroke
				(width 0.1)
				(type default)
			)
			(layer "F.Fab")
		)
		(fp_line
			(start -0.12065 -0.305054)
			(end -0.12065 -0.2794)
			(stroke
				(width 0.1)
				(type default)
			)
			(layer "F.Fab")
		)
		(pad "1" smd circle
			(at -0.40005 0 270)
			(size 0 0)
			(layers "F.Cu" "F.Mask" "F.Paste")
			(net "P3V3_AUX")
		)
		(pad "2" smd circle
			(at 0.40005 0 270)
			(size 0 0)
			(layers "F.Cu" "F.Mask" "F.Paste")
			(net "GND")
		)
	)
	(footprint ""
		(layer "F.Cu")
		(at 356.565962 -256.012188 90)
		(property "Reference" "C3895"
			(at 0 0 90)
			(layer "F.SilkS")
			(hide yes)
			(effects
				(font
					(size 1.27 1.27)
				)
			)
		)
		(property "Value" ""
			(at 0 0 90)
			(layer "F.Fab")
			(effects
				(font
					(size 1.27 1.27)
				)
			)
		)
		(duplicate_pad_numbers_are_jumpers no)
		(fp_line
			(start 0.7874 -0.4064)
			(end 0.7874 0.4064)
			(stroke
				(width 0.1524)
				(type default)
			)
			(layer "F.SilkS")
		)
		(fp_line
			(start -0.7874 -0.4064)
			(end 0.7874 -0.4064)
			(stroke
				(width 0.1524)
				(type default)
			)
			(layer "F.SilkS")
		)
		(fp_line
			(start 0.7874 0.4064)
			(end -0.7874 0.4064)
			(stroke
				(width 0.1524)
				(type default)
			)
			(layer "F.SilkS")
		)
		(fp_line
			(start -0.7874 0.4064)
			(end -0.7874 -0.4064)
			(stroke
				(width 0.1524)
				(type default)
			)
			(layer "F.SilkS")
		)
		(fp_line
			(start -0.12065 -0.305054)
			(end -0.12065 -0.2794)
			(stroke
				(width 0.1)
				(type default)
			)
			(layer "F.Fab")
		)
		(fp_line
			(start -0.67945 -0.305054)
			(end -0.12065 -0.305054)
			(stroke
				(width 0.1)
				(type default)
			)
			(layer "F.Fab")
		)
		(fp_line
			(start 0.67945 -0.3048)
			(end 0.67945 0.3048)
			(stroke
				(width 0.1)
				(type default)
			)
			(layer "F.Fab")
		)
		(fp_line
			(start 0.12065 -0.3048)
			(end 0.67945 -0.3048)
			(stroke
				(width 0.1)
				(type default)
			)
			(layer "F.Fab")
		)
		(fp_line
			(start 0.12065 -0.2794)
			(end 0.12065 -0.3048)
			(stroke
				(width 0.1)
				(type default)
			)
			(layer "F.Fab")
		)
		(fp_line
			(start -0.12065 -0.2794)
			(end 0.12065 -0.2794)
			(stroke
				(width 0.1)
				(type default)
			)
			(layer "F.Fab")
		)
		(fp_line
			(start 0.120396 0.2794)
			(end -0.12065 0.2794)
			(stroke
				(width 0.1)
				(type default)
			)
			(layer "F.Fab")
		)
		(fp_line
			(start -0.12065 0.2794)
			(end -0.12065 0.3048)
			(stroke
				(width 0.1)
				(type default)
			)
			(layer "F.Fab")
		)
		(fp_line
			(start 0.67945 0.3048)
			(end 0.120396 0.3048)
			(stroke
				(width 0.1)
				(type default)
			)
			(layer "F.Fab")
		)
		(fp_line
			(start 0.120396 0.3048)
			(end 0.120396 0.2794)
			(stroke
				(width 0.1)
				(type default)
			)
			(layer "F.Fab")
		)
		(fp_line
			(start -0.12065 0.3048)
			(end -0.67945 0.3048)
			(stroke
				(width 0.1)
				(type default)
			)
			(layer "F.Fab")
		)
		(fp_line
			(start -0.67945 0.3048)
			(end -0.67945 -0.305054)
			(stroke
				(width 0.1)
				(type default)
			)
			(layer "F.Fab")
		)
		(pad "1" smd circle
			(at -0.40005 0 90)
			(size 0 0)
			(layers "F.Cu" "F.Mask" "F.Paste")
			(net "PVDDCR_SOC_P0")
		)
		(pad "2" smd circle
			(at 0.40005 0 90)
			(size 0 0)
			(layers "F.Cu" "F.Mask" "F.Paste")
			(net "GND")
		)
	)
)
